(kicad_pcb
	(version 20241229)
	(generator "pcbnew")
	(generator_version "9.0")
	(general
		(thickness 1.6296)
		(legacy_teardrops no)
	)
	(paper "A3")
	(title_block
		(title "Thunderbolt to 10GbE adapter")
		(date "2026-04-21")
		(rev "1.1.0")
		(company "Antmicro Ltd")
		(comment 1 "www.antmicro.com")
		(comment 9 "footprints 224-227 of 703")
	)
	(layers
		(0 "F.Cu" signal)
		(4 "In1.Cu" signal)
		(6 "In2.Cu" signal)
		(8 "In3.Cu" signal)
		(10 "In4.Cu" signal)
		(12 "In5.Cu" signal)
		(14 "In6.Cu" signal)
		(2 "B.Cu" signal)
		(9 "F.Adhes" user "F.Adhesive")
		(11 "B.Adhes" user "B.Adhesive")
		(13 "F.Paste" user)
		(15 "B.Paste" user)
		(5 "F.SilkS" user "F.Silkscreen")
		(7 "B.SilkS" user "B.Silkscreen")
		(1 "F.Mask" user)
		(3 "B.Mask" user)
		(17 "Dwgs.User" user "User.Drawings")
		(19 "Cmts.User" user "User.Comments")
		(21 "Eco1.User" user "User.Eco1")
		(23 "Eco2.User" user "User.Eco2")
		(25 "Edge.Cuts" user)
		(27 "Margin" user)
		(31 "F.CrtYd" user "F.Courtyard")
		(29 "B.CrtYd" user "B.Courtyard")
		(35 "F.Fab" user)
		(33 "B.Fab" user)
	)
	(footprint "antmicro-footprints:R_0402_1005Metric"
		(layer "F.Cu")
		(at 138 70.2)
		(descr "Resistor SMD 0402")
		(tags "resistor SMD 0402")
		(property "Reference" "RT1"
			(at -1.8 -0.6 0)
			(layer "F.SilkS")
			(effects
				(font
					(size 0.7 0.7)
					(thickness 0.15)
				)
				(justify left bottom)
			)
		)
		(property "Value" "RT_NTC_10k_0402"
			(at -1.011843 1.772047 0)
			(layer "F.Fab")
			(effects
				(font
					(size 0.7 0.7)
					(thickness 0.15)
				)
				(justify left bottom)
			)
		)
		(property "Datasheet" "https://eu.mouser.com/datasheet/2/281/r44e-522712.pdf"
			(at 0 0 0)
			(layer "F.Fab")
			(hide yes)
			(effects
				(font
					(size 1.27 1.27)
					(thickness 0.15)
				)
			)
		)
		(property "Description" "10k NTC in 0402 package with 5V max voltage"
			(at 0 0 0)
			(layer "F.Fab")
			(hide yes)
			(effects
				(font
					(size 1.27 1.27)
					(thickness 0.15)
				)
			)
		)
		(property "MPN" "NCP15XH103F03RC"
			(at 0 0 0)
			(unlocked yes)
			(layer "F.Fab")
			(hide yes)
			(effects
				(font
					(size 1 1)
					(thickness 0.15)
				)
			)
		)
		(property "Manufacturer" "Murata"
			(at 0 0 0)
			(unlocked yes)
			(layer "F.Fab")
			(hide yes)
			(effects
				(font
					(size 1 1)
					(thickness 0.15)
				)
			)
		)
		(property "License" "Apache-2.0"
			(at 0 0 0)
			(unlocked yes)
			(layer "F.Fab")
			(hide yes)
			(effects
				(font
					(size 1 1)
					(thickness 0.15)
				)
			)
		)
		(property "Author" "Antmicro"
			(at 0 0 0)
			(unlocked yes)
			(layer "F.Fab")
			(hide yes)
			(effects
				(font
					(size 1 1)
					(thickness 0.15)
				)
			)
		)
		(property "Val" "10k"
			(at 0 0 0)
			(unlocked yes)
			(layer "F.Fab")
			(hide yes)
			(effects
				(font
					(size 1 1)
					(thickness 0.15)
				)
			)
		)
		(property "Voltage" "5V"
			(at 0 0 0)
			(unlocked yes)
			(layer "F.Fab")
			(hide yes)
			(effects
				(font
					(size 1 1)
					(thickness 0.15)
				)
			)
		)
		(sheetname "/Fan controller/")
		(sheetfile "fan-controller.kicad_sch")
		(attr smd)
		(fp_rect
			(start -0.925 -0.47)
			(end 0.925 0.47)
			(stroke
				(width 0.05)
				(type default)
			)
			(fill no)
			(layer "F.CrtYd")
		)
		(fp_rect
			(start -0.5 -0.25)
			(end 0.5 0.25)
			(stroke
				(width 0.15)
				(type solid)
			)
			(fill no)
			(layer "F.Fab")
		)
		(fp_text user "License: Apache-2.0"
			(at -0.95 5.169 0)
			(layer "F.Fab")
			(effects
				(font
					(size 0.7 0.7)
					(thickness 0.15)
				)
				(justify left bottom)
			)
		)
		(fp_text user "Author: Antmicro"
			(at -0.95 4.169 0)
			(layer "F.Fab")
			(effects
				(font
					(size 0.7 0.7)
					(thickness 0.15)
				)
				(justify left bottom)
			)
		)
		(fp_text user "${REFERENCE}"
			(at -0.95 3.168 0)
			(layer "F.Fab")
			(effects
				(font
					(size 0.7 0.7)
					(thickness 0.15)
				)
				(justify left bottom)
			)
		)
		(pad "1" smd roundrect
			(at -0.48 0)
			(size 0.59 0.64)
			(layers "F.Cu" "F.Mask" "F.Paste")
			(roundrect_rratio 0.25)
			(net 446 "Net-(R216-Pad1)")
			(pintype "passive")
		)
		(pad "2" smd roundrect
			(at 0.48 0)
			(size 0.59 0.64)
			(layers "F.Cu" "F.Mask" "F.Paste")
			(roundrect_rratio 0.25)
			(net 23 "GND")
			(pintype "passive")
		)
	)
	(footprint "antmicro-footprints:C_0402_1005Metric"
		(layer "F.Cu")
		(at 165.304999 99.204999 -90)
		(descr "Capacitor SMD 0402")
		(tags "capacitor SMD 0402")
		(property "Reference" "C164"
			(at 0 -7.695 270)
			(layer "F.SilkS")
			(effects
				(font
					(size 0.7 0.7)
					(thickness 0.15)
				)
			)
		)
		(property "Value" "C_100n_0402"
			(at -1.022927 2.155213 270)
			(layer "F.Fab")
			(effects
				(font
					(size 0.7 0.7)
					(thickness 0.15)
				)
				(justify left bottom)
			)
		)
		(property "Datasheet" "https://www.murata.com/products/productdetail?partno=GRM155R61H104KE14%23"
			(at 0 0 270)
			(layer "F.Fab")
			(hide yes)
			(effects
				(font
					(size 1.27 1.27)
					(thickness 0.15)
				)
			)
		)
		(property "Description" "SMD Multilayer Ceramic Capacitor, 0.1 µF, 50 V, 0402 [1005 Metric], ± 10%, X5R, GRM Series"
			(at 0 0 270)
			(layer "F.Fab")
			(hide yes)
			(effects
				(font
					(size 1.27 1.27)
					(thickness 0.15)
				)
			)
		)
		(property "MPN" "GRM155R61H104KE14D"
			(at 0 0 270)
			(unlocked yes)
			(layer "F.Fab")
			(hide yes)
			(effects
				(font
					(size 1 1)
					(thickness 0.15)
				)
			)
		)
		(property "Val" "100n"
			(at 0 0 270)
			(unlocked yes)
			(layer "F.Fab")
			(hide yes)
			(effects
				(font
					(size 1 1)
					(thickness 0.15)
				)
			)
		)
		(property "Voltage" "50V"
			(at 0 0 270)
			(unlocked yes)
			(layer "F.Fab")
			(hide yes)
			(effects
				(font
					(size 1 1)
					(thickness 0.15)
				)
			)
		)
		(property "Dielectric" "X5R"
			(at 0 0 270)
			(unlocked yes)
			(layer "F.Fab")
			(hide yes)
			(effects
				(font
					(size 1 1)
					(thickness 0.15)
				)
			)
		)
		(property "Manufacturer" "Murata"
			(at 0 0 270)
			(unlocked yes)
			(layer "F.Fab")
			(hide yes)
			(effects
				(font
					(size 1 1)
					(thickness 0.15)
				)
			)
		)
		(property "License" "Apache-2.0"
			(at 0 0 270)
			(unlocked yes)
			(layer "F.Fab")
			(hide yes)
			(effects
				(font
					(size 1 1)
					(thickness 0.15)
				)
			)
		)
		(property "Author" "Antmicro"
			(at 0 0 270)
			(unlocked yes)
			(layer "F.Fab")
			(hide yes)
			(effects
				(font
					(size 1 1)
					(thickness 0.15)
				)
			)
		)
		(sheetname "/X710-AT2 power/")
		(sheetfile "x710-at2-power.kicad_sch")
		(attr smd)
		(fp_rect
			(start -0.925 -0.47)
			(end 0.925 0.47)
			(stroke
				(width 0.05)
				(type default)
			)
			(fill no)
			(layer "F.CrtYd")
		)
		(fp_line
			(start -0.494 0.248)
			(end -0.494 -0.25)
			(stroke
				(width 0.15)
				(type solid)
			)
			(layer "F.Fab")
		)
		(fp_line
			(start 0.504 0.248)
			(end -0.494 0.248)
			(stroke
				(width 0.15)
				(type solid)
			)
			(layer "F.Fab")
		)
		(fp_line
			(start -0.494 -0.25)
			(end 0.504 -0.25)
			(stroke
				(width 0.15)
				(type solid)
			)
			(layer "F.Fab")
		)
		(fp_line
			(start 0.504 -0.25)
			(end 0.504 0.248)
			(stroke
				(width 0.15)
				(type solid)
			)
			(layer "F.Fab")
		)
		(fp_text user "License: Apache-2.0"
			(at -0.939 5.799 270)
			(layer "F.Fab")
			(effects
				(font
					(size 0.7 0.7)
					(thickness 0.15)
				)
				(justify left bottom)
			)
		)
		(fp_text user "Author: Antmicro"
			(at -0.939 3.399 270)
			(layer "F.Fab")
			(effects
				(font
					(size 0.7 0.7)
					(thickness 0.15)
				)
				(justify left bottom)
			)
		)
		(fp_text user "${REFERENCE}"
			(at -0.939 4.599 270)
			(layer "F.Fab")
			(effects
				(font
					(size 0.7 0.7)
					(thickness 0.15)
				)
				(justify left bottom)
			)
		)
		(pad "1" smd roundrect
			(at -0.48 0 270)
			(size 0.59 0.64)
			(layers "F.Cu" "F.Mask" "F.Paste")
			(roundrect_rratio 0.25)
			(net 23 "GND")
			(pintype "passive")
		)
		(pad "2" smd roundrect
			(at 0.48 0 270)
			(size 0.59 0.64)
			(layers "F.Cu" "F.Mask" "F.Paste")
			(roundrect_rratio 0.25)
			(net 136 "+1V0")
			(pintype "passive")
		)
	)
	(footprint "antmicro-footprints:C_0402_1005Metric"
		(layer "F.Cu")
		(at 138 74.75)
		(descr "Capacitor SMD 0402")
		(tags "capacitor SMD 0402")
		(property "Reference" "C271"
			(at -3.8 0.45 0)
			(layer "F.SilkS")
			(effects
				(font
					(size 0.7 0.7)
					(thickness 0.15)
				)
				(justify left bottom)
			)
		)
		(property "Value" "C_220n_16V_0402"
			(at -1.022927 2.155213 0)
			(layer "F.Fab")
			(effects
				(font
					(size 0.7 0.7)
					(thickness 0.15)
				)
				(justify left bottom)
			)
		)
		(property "Datasheet" "https://www.murata.com/products/productdetail?partno=GRM155R71C224KA12%23"
			(at 0 0 0)
			(layer "F.Fab")
			(hide yes)
			(effects
				(font
					(size 1.27 1.27)
					(thickness 0.15)
				)
			)
		)
		(property "Description" "SMD Multilayer Ceramic Capacitor, 0.22 µF, 16 V, 0402 [1005 Metric], ± 10%, X7R, GRM Series"
			(at 0 0 0)
			(layer "F.Fab")
			(hide yes)
			(effects
				(font
					(size 1.27 1.27)
					(thickness 0.15)
				)
			)
		)
		(property "MPN" "GRM155R71C224KA12D"
			(at 0 0 0)
			(unlocked yes)
			(layer "F.Fab")
			(hide yes)
			(effects
				(font
					(size 1 1)
					(thickness 0.15)
				)
			)
		)
		(property "Manufacturer" "Murata"
			(at 0 0 0)
			(unlocked yes)
			(layer "F.Fab")
			(hide yes)
			(effects
				(font
					(size 1 1)
					(thickness 0.15)
				)
			)
		)
		(property "License" "Apache-2.0"
			(at 0 0 0)
			(unlocked yes)
			(layer "F.Fab")
			(hide yes)
			(effects
				(font
					(size 1 1)
					(thickness 0.15)
				)
			)
		)
		(property "Author" "Antmicro"
			(at 0 0 0)
			(unlocked yes)
			(layer "F.Fab")
			(hide yes)
			(effects
				(font
					(size 1 1)
					(thickness 0.15)
				)
			)
		)
		(property "Val" "220n"
			(at 0 0 0)
			(unlocked yes)
			(layer "F.Fab")
			(hide yes)
			(effects
				(font
					(size 1 1)
					(thickness 0.15)
				)
			)
		)
		(property "Voltage" "16V"
			(at 0 0 0)
			(unlocked yes)
			(layer "F.Fab")
			(hide yes)
			(effects
				(font
					(size 1 1)
					(thickness 0.15)
				)
			)
		)
		(property "Dielectric" "X7R"
			(at 0 0 0)
			(unlocked yes)
			(layer "F.Fab")
			(hide yes)
			(effects
				(font
					(size 1 1)
					(thickness 0.15)
				)
			)
		)
		(sheetname "/X710-AT2 PCIe/")
		(sheetfile "x710-at2-pcie.kicad_sch")
		(attr smd)
		(fp_rect
			(start -0.925 -0.47)
			(end 0.925 0.47)
			(stroke
				(width 0.05)
				(type default)
			)
			(fill no)
			(layer "F.CrtYd")
		)
		(fp_line
			(start -0.494 -0.25)
			(end 0.504 -0.25)
			(stroke
				(width 0.15)
				(type solid)
			)
			(layer "F.Fab")
		)
		(fp_line
			(start -0.494 0.248)
			(end -0.494 -0.25)
			(stroke
				(width 0.15)
				(type solid)
			)
			(layer "F.Fab")
		)
		(fp_line
			(start 0.504 -0.25)
			(end 0.504 0.248)
			(stroke
				(width 0.15)
				(type solid)
			)
			(layer "F.Fab")
		)
		(fp_line
			(start 0.504 0.248)
			(end -0.494 0.248)
			(stroke
				(width 0.15)
				(type solid)
			)
			(layer "F.Fab")
		)
		(fp_text user "License: Apache-2.0"
			(at -0.939 5.799 0)
			(layer "F.Fab")
			(effects
				(font
					(size 0.7 0.7)
					(thickness 0.15)
				)
				(justify left bottom)
			)
		)
		(fp_text user "${REFERENCE}"
			(at -0.939 4.599 0)
			(layer "F.Fab")
			(effects
				(font
					(size 0.7 0.7)
					(thickness 0.15)
				)
				(justify left bottom)
			)
		)
		(fp_text user "Author: Antmicro"
			(at -0.939 3.399 0)
			(layer "F.Fab")
			(effects
				(font
					(size 0.7 0.7)
					(thickness 0.15)
				)
				(justify left bottom)
			)
		)
		(pad "1" smd roundrect
			(at -0.48 0)
			(size 0.59 0.64)
			(layers "F.Cu" "F.Mask" "F.Paste")
			(roundrect_rratio 0.25)
			(net 600 "/TB Controller/PCIex4.TX1+")
			(pintype "passive")
		)
		(pad "2" smd roundrect
			(at 0.48 0)
			(size 0.59 0.64)
			(layers "F.Cu" "F.Mask" "F.Paste")
			(roundrect_rratio 0.25)
			(net 29 "/X710-AT2 PCIe/PCIe_{x4}_AC.TX1+")
			(pintype "passive")
		)
	)
	(footprint "antmicro-footprints:R_0402_1005Metric"
		(layer "F.Cu")
		(at 159.105 67.125 -90)
		(descr "Resistor SMD 0402")
		(tags "resistor SMD 0402")
		(property "Reference" "R188"
			(at -12.324999 -20.295 270)
			(layer "F.SilkS")
			(effects
				(font
					(size 0.7 0.7)
					(thickness 0.15)
				)
			)
		)
		(property "Value" "R_22R_0402"
			(at -1.011843 1.772047 270)
			(layer "F.Fab")
			(effects
				(font
					(size 0.7 0.7)
					(thickness 0.15)
				)
				(justify left bottom)
			)
		)
		(property "Datasheet" "https://www.bourns.com/docs/product-datasheets/cr.pdf"
			(at 0 0 270)
			(layer "F.Fab")
			(hide yes)
			(effects
				(font
					(size 1.27 1.27)
					(thickness 0.15)
				)
			)
		)
		(property "Description" "SMD Chip Resistor, 22 ohm, ± 1%, 62.5 mW, 0402 [1005 Metric], Thick Film, General Purpose"
			(at 0 0 270)
			(layer "F.Fab")
			(hide yes)
			(effects
				(font
					(size 1.27 1.27)
					(thickness 0.15)
				)
			)
		)
		(property "MPN" "CR0402-FX-22R0GLF"
			(at 0 0 270)
			(unlocked yes)
			(layer "F.Fab")
			(hide yes)
			(effects
				(font
					(size 1 1)
					(thickness 0.15)
				)
			)
		)
		(property "Manufacturer" "Bourns"
			(at 0 0 270)
			(unlocked yes)
			(layer "F.Fab")
			(hide yes)
			(effects
				(font
					(size 1 1)
					(thickness 0.15)
				)
			)
		)
		(property "License" "Apache-2.0"
			(at 0 0 270)
			(unlocked yes)
			(layer "F.Fab")
			(hide yes)
			(effects
				(font
					(size 1 1)
					(thickness 0.15)
				)
			)
		)
		(property "Author" "Antmicro"
			(at 0 0 270)
			(unlocked yes)
			(layer "F.Fab")
			(hide yes)
			(effects
				(font
					(size 1 1)
					(thickness 0.15)
				)
			)
		)
		(property "Val" "22R"
			(at 0 0 270)
			(unlocked yes)
			(layer "F.Fab")
			(hide yes)
			(effects
				(font
					(size 1 1)
					(thickness 0.15)
				)
			)
		)
		(property "Tolerance" "1%"
			(at 0 0 270)
			(unlocked yes)
			(layer "F.Fab")
			(hide yes)
			(effects
				(font
					(size 1 1)
					(thickness 0.15)
				)
			)
		)
		(sheetname "/X710-AT2 10GbE/")
		(sheetfile "x710-at2-10gbe.kicad_sch")
		(attr smd)
		(fp_rect
			(start -0.925 -0.47)
			(end 0.925 0.47)
			(stroke
				(width 0.05)
				(type default)
			)
			(fill no)
			(layer "F.CrtYd")
		)
		(fp_rect
			(start -0.5 -0.25)
			(end 0.5 0.25)
			(stroke
				(width 0.15)
				(type solid)
			)
			(fill no)
			(layer "F.Fab")
		)
		(fp_text user "License: Apache-2.0"
			(at -0.95 5.169 270)
			(layer "F.Fab")
			(effects
				(font
					(size 0.7 0.7)
					(thickness 0.15)
				)
				(justify left bottom)
			)
		)
		(fp_text user "Author: Antmicro"
			(at -0.95 4.169 270)
			(layer "F.Fab")
			(effects
				(font
					(size 0.7 0.7)
					(thickness 0.15)
				)
				(justify left bottom)
			)
		)
		(fp_text user "${REFERENCE}"
			(at -0.95 3.168 270)
			(layer "F.Fab")
			(effects
				(font
					(size 0.7 0.7)
					(thickness 0.15)
				)
				(justify left bottom)
			)
		)
		(pad "1" smd roundrect
			(at -0.48 0 270)
			(size 0.59 0.64)
			(layers "F.Cu" "F.Mask" "F.Paste")
			(roundrect_rratio 0.25)
			(net 112 "/X710-AT2 10GbE/25MHZ_OSC_R.+")
			(pintype "passive")
		)
		(pad "2" smd roundrect
			(at 0.48 0 270)
			(size 0.59 0.64)
			(layers "F.Cu" "F.Mask" "F.Paste")
			(roundrect_rratio 0.25)
			(net 25 "/X710-AT2 10GbE/25MHZ_OSC_AC.+")
			(pintype "passive")
		)
	)
)
